# BASEBOARD_FAB2 (Tioga Pass) — schematic netlist excerpt (pin names and nets, part order shuffled) for the footprints in the layout excerpt that follows; sources: Cadence DE-HDL packaged netlist, KiCad conversion of Wiwynn_Tioga_Pass_MB.brd

R9P15  RES  0.0 5% CHIP  pkg 0402  page 200 : A = A_HSC_LOW_DRAIN ; B = IRQ_OC_DETECT_N
L25W2  IND-68NH-15-GP  pkg DISCRET-GC1  page 252 : \1\ = BMC_VGA_GREEN ; \2\ = V_IO_G_J
C2T32  CAP_A  0.1UF 16V 10% X7R  pkg 0402V  page 93 : A = P0V7_GTL2104_5_VREF ; B = GND

(kicad_pcb
	(version 20260206)
	(generator "pcbnew")
	(generator_version "10.0")
	(general
		(thickness 1.6)
		(legacy_teardrops no)
	)
	(paper "A4")
	(title_block
		(title "Wiwynn_Tioga_Pass_MB.brd")
		(comment 1 "Tioga Pass / footprints 4133-4135 of 4770")
	)
	(layers
		(0 "F.Cu" signal "TOP")
		(4 "In1.Cu" signal "L2GND")
		(6 "In2.Cu" signal "L3")
		(8 "In3.Cu" signal "L4GND")
		(10 "In4.Cu" signal "L5")
		(12 "In5.Cu" signal "L6GND")
		(14 "In6.Cu" signal "L7VCC")
		(16 "In7.Cu" signal "L8VCC")
		(18 "In8.Cu" signal "L9GND")
		(20 "In9.Cu" signal "L10")
		(22 "In10.Cu" signal "L11GND")
		(24 "In11.Cu" signal "L12")
		(26 "In12.Cu" signal "L13GND")
		(2 "B.Cu" signal "BOTTOM")
		(9 "F.Adhes" user "F.Adhesive")
		(11 "B.Adhes" user "B.Adhesive")
		(13 "F.Paste" user "Package Geometry/Pastemask Top")
		(15 "B.Paste" user "Package Geometry/Pastemask Bottom")
		(5 "F.SilkS" user "Ref Des/Silkscreen Top")
		(7 "B.SilkS" user "Ref Des/Silkscreen Bottom")
		(1 "F.Mask" user "Board Geometry/Soldermask Top")
		(3 "B.Mask" user "Board Geometry/Soldermask Bottom")
		(17 "Dwgs.User" user "User.Drawings")
		(19 "Cmts.User" user "User.Comments")
		(21 "Eco1.User" user "User.Eco1")
		(23 "Eco2.User" user "User.Eco2")
		(25 "Edge.Cuts" user "Board Geometry/Outline")
		(27 "Margin" user)
		(31 "F.CrtYd" user "Package Geometry/Place Bound Top")
		(29 "B.CrtYd" user "Package Geometry/Place Bound Bottom")
		(35 "F.Fab" user "Ref Des/Assembly Top")
		(33 "B.Fab" user "Ref Des/Assembly Bottom")
	)
	(footprint ""
		(layer "B.Cu")
		(at 16.256 -81.153 90)
		(property "Reference" "R9P15"
			(at 0 0 90)
			(layer "B.SilkS")
			(hide yes)
			(effects
				(font
					(size 1.27 1.27)
				)
				(justify mirror)
			)
		)
		(property "Value" ""
			(at 0 0 90)
			(layer "B.Fab")
			(effects
				(font
					(size 1.27 1.27)
				)
				(justify mirror)
			)
		)
		(duplicate_pad_numbers_are_jumpers no)
		(fp_poly
			(pts
				(xy 0.2794 -0.1016) (xy -0.2794 -0.1016) (xy -0.2794 0.9906) (xy 0.2794 0.9906)
			)
			(stroke
				(width 0)
				(type default)
			)
			(fill no)
			(layer "B.CrtYd")
		)
		(fp_line
			(start 0.2794 -0.1016)
			(end 0.2794 0.9906)
			(stroke
				(width 0.1)
				(type default)
			)
			(layer "B.Fab")
		)
		(fp_line
			(start -0.2794 -0.1016)
			(end 0.2794 -0.1016)
			(stroke
				(width 0.1)
				(type default)
			)
			(layer "B.Fab")
		)
		(fp_line
			(start 0.2794 0.9906)
			(end -0.2794 0.9906)
			(stroke
				(width 0.1)
				(type default)
			)
			(layer "B.Fab")
		)
		(fp_line
			(start -0.2794 0.9906)
			(end -0.2794 -0.1016)
			(stroke
				(width 0.1)
				(type default)
			)
			(layer "B.Fab")
		)
		(pad "1" smd rect
			(at 0 0 270)
			(size 0.508 0.508)
			(layers "B.Cu" "B.Mask" "B.Paste")
			(net "A_HSC_LOW_DRAIN")
		)
		(pad "2" smd rect
			(at 0 0.889 270)
			(size 0.508 0.508)
			(layers "B.Cu" "B.Mask" "B.Paste")
			(net "IRQ_OC_DETECT_N")
		)
		(zone
			(layer "B.Cu")
			(hatch none 0.5)
			(connect_pads
				(clearance 0)
			)
			(min_thickness 0.25)
			(keepout
				(tracks allowed)
				(vias not_allowed)
				(pads allowed)
				(copperpour not_allowed)
				(footprints allowed)
			)
			(placement
				(enabled no)
				(sheetname "")
			)
			(fill
				(thermal_gap 0.5)
				(thermal_bridge_width 0.5)
				(island_removal_mode 0)
			)
			(polygon
				(pts
					(xy 16.51 -81.407) (xy 16.51 -80.899) (xy 16.891 -80.899) (xy 16.891 -81.407)
				)
			)
		)
		(zone
			(layer "B.Cu")
			(hatch none 0.5)
			(connect_pads
				(clearance 0)
			)
			(min_thickness 0.25)
			(keepout
				(tracks not_allowed)
				(vias allowed)
				(pads allowed)
				(copperpour not_allowed)
				(footprints allowed)
			)
			(placement
				(enabled no)
				(sheetname "")
			)
			(fill
				(thermal_gap 0.5)
				(thermal_bridge_width 0.5)
				(island_removal_mode 0)
			)
			(polygon
				(pts
					(xy 16.891 -81.407) (xy 16.891 -80.899) (xy 16.51 -80.899) (xy 16.51 -81.407)
				)
			)
		)
	)
	(footprint ""
		(layer "B.Cu")
		(at 375.0945 -44.9072 90)
		(property "Reference" "C2T32"
			(at 0 0 90)
			(layer "B.SilkS")
			(hide yes)
			(effects
				(font
					(size 1.27 1.27)
				)
				(justify mirror)
			)
		)
		(property "Value" ""
			(at 0 0 90)
			(layer "B.Fab")
			(effects
				(font
					(size 1.27 1.27)
				)
				(justify mirror)
			)
		)
		(duplicate_pad_numbers_are_jumpers no)
		(fp_poly
			(pts
				(xy -0.3048 -0.1016) (xy -0.3048 0.9906) (xy 0.3048 0.9906) (xy 0.3048 -0.1016)
			)
			(stroke
				(width 0)
				(type default)
			)
			(fill no)
			(layer "B.CrtYd")
		)
		(fp_line
			(start 0.3048 -0.1016)
			(end 0.3048 0.9906)
			(stroke
				(width 0.1)
				(type default)
			)
			(layer "B.Fab")
		)
		(fp_line
			(start -0.3048 -0.1016)
			(end 0.3048 -0.1016)
			(stroke
				(width 0.1)
				(type default)
			)
			(layer "B.Fab")
		)
		(fp_line
			(start 0.3048 0.9906)
			(end -0.3048 0.9906)
			(stroke
				(width 0.1)
				(type default)
			)
			(layer "B.Fab")
		)
		(fp_line
			(start -0.3048 0.9906)
			(end -0.3048 -0.1016)
			(stroke
				(width 0.1)
				(type default)
			)
			(layer "B.Fab")
		)
		(pad "1" smd rect
			(at 0 0 270)
			(size 0.508 0.508)
			(layers "B.Cu" "B.Mask" "B.Paste")
			(net "P0V7_GTL2104_5_VREF")
		)
		(pad "2" smd rect
			(at 0 0.889 270)
			(size 0.508 0.508)
			(layers "B.Cu" "B.Mask" "B.Paste")
			(net "GND")
		)
		(zone
			(layer "B.Cu")
			(hatch none 0.5)
			(connect_pads
				(clearance 0)
			)
			(min_thickness 0.25)
			(keepout
				(tracks allowed)
				(vias not_allowed)
				(pads allowed)
				(copperpour not_allowed)
				(footprints allowed)
			)
			(placement
				(enabled no)
				(sheetname "")
			)
			(fill
				(thermal_gap 0.5)
				(thermal_bridge_width 0.5)
				(island_removal_mode 0)
			)
			(polygon
				(pts
					(xy 375.3485 -45.1612) (xy 375.3485 -44.6532) (xy 375.7295 -44.6532) (xy 375.7295 -45.1612)
				)
			)
		)
		(zone
			(layer "B.Cu")
			(hatch none 0.5)
			(connect_pads
				(clearance 0)
			)
			(min_thickness 0.25)
			(keepout
				(tracks not_allowed)
				(vias allowed)
				(pads allowed)
				(copperpour not_allowed)
				(footprints allowed)
			)
			(placement
				(enabled no)
				(sheetname "")
			)
			(fill
				(thermal_gap 0.5)
				(thermal_bridge_width 0.5)
				(island_removal_mode 0)
			)
			(polygon
				(pts
					(xy 375.7295 -45.1612) (xy 375.7295 -44.6532) (xy 375.3485 -44.6532) (xy 375.3485 -45.1612)
				)
			)
		)
	)
	(footprint ""
		(layer "B.Cu")
		(at 418.846 -23.495 90)
		(property "Reference" "L25W2"
			(at 0 0 90)
			(layer "B.SilkS")
			(hide yes)
			(effects
				(font
					(size 1.27 1.27)
				)
				(justify mirror)
			)
		)
		(property "Value" "*"
			(at -0.0254 -2.8829 90)
			(unlocked yes)
			(layer "B.Fab")
			(hide yes)
			(effects
				(font
					(size 1.27 1.016)
					(thickness 0.1524)
				)
				(justify mirror)
			)
		)
		(property "Device Type" "IND-68NH-15-GP_DISCRET-GC1-INDA"
			(at -0.0254 -4.4069 90)
			(unlocked yes)
			(layer "B.Fab")
			(hide yes)
			(effects
				(font
					(size 1.27 1.016)
					(thickness 0.1524)
				)
				(justify mirror)
			)
		)
		(duplicate_pad_numbers_are_jumpers no)
		(fp_line
			(start -0.254 0)
			(end 0.254 0)
			(stroke
				(width 0.2032)
				(type default)
			)
			(layer "B.SilkS")
		)
		(fp_rect
			(start 0.5842 1.3335)
			(end -0.5842 -1.3335)
			(stroke
				(width 0)
				(type default)
			)
			(fill no)
			(layer "B.CrtYd")
		)
		(fp_rect
			(start 0.5842 1.3335)
			(end -0.5842 -1.3335)
			(stroke
				(width 0)
				(type default)
			)
			(fill no)
			(layer "B.Fab")
		)
		(pad "1" smd custom
			(at 0 -0.762 270)
			(size 0.2159 0.2159)
			(layers "B.Cu" "B.Mask" "B.Paste")
			(net "BMC_VGA_GREEN")
			(options
				(clearance outline)
				(anchor circle)
			)
			(primitives
				(gr_poly
					(pts
						(arc
							(start -0.3302 0.4318)
							(mid -0.402042 0.402042)
							(end -0.4318 0.3302)
						)
						(arc
							(start -0.4318 -0.3302)
							(mid -0.402042 -0.402042)
							(end -0.3302 -0.4318)
						)
						(arc
							(start 0.3302 -0.4318)
							(mid 0.402042 -0.402042)
							(end 0.4318 -0.3302)
						)
						(arc
							(start 0.4318 0.3302)
							(mid 0.402042 0.402042)
							(end 0.3302 0.4318)
						)
					)
					(width 0)
					(fill yes)
				)
			)
		)
		(pad "2" smd custom
			(at 0 0.762 270)
			(size 0.2159 0.2159)
			(layers "B.Cu" "B.Mask" "B.Paste")
			(net "V_IO_G_J")
			(options
				(clearance outline)
				(anchor circle)
			)
			(primitives
				(gr_poly
					(pts
						(arc
							(start -0.3302 0.4318)
							(mid -0.402042 0.402042)
							(end -0.4318 0.3302)
						)
						(arc
							(start -0.4318 -0.3302)
							(mid -0.402042 -0.402042)
							(end -0.3302 -0.4318)
						)
						(arc
							(start 0.3302 -0.4318)
							(mid 0.402042 -0.402042)
							(end 0.4318 -0.3302)
						)
						(arc
							(start 0.4318 0.3302)
							(mid 0.402042 0.402042)
							(end 0.3302 0.4318)
						)
					)
					(width 0)
					(fill yes)
				)
			)
		)
	)
)
